(kicad_pcb
	(version 20260206)
	(generator "pcbnew")
	(generator_version "10.0")
	(general
		(thickness 1.6)
		(legacy_teardrops no)
	)
	(paper "A4")
	(title_block
		(title "peb — Lightning_PEB_BRD.brd")
		(comment 1 "Lightning (Wiwynn / Facebook NVMe JBOF) / footprints 269-276 of 2563")
	)
	(layers
		(0 "F.Cu" signal "TOP")
		(4 "In1.Cu" signal "L2GND")
		(6 "In2.Cu" signal "L3")
		(8 "In3.Cu" signal "L4VCC")
		(10 "In4.Cu" signal "L5VCC")
		(12 "In5.Cu" signal "L6")
		(14 "In6.Cu" signal "L7GND")
		(2 "B.Cu" signal "BOTTOM")
		(9 "F.Adhes" user "F.Adhesive")
		(11 "B.Adhes" user "B.Adhesive")
		(13 "F.Paste" user "Package Geometry/Pastemask Top")
		(15 "B.Paste" user "Package Geometry/Pastemask Bottom")
		(5 "F.SilkS" user "Ref Des/Silkscreen Top")
		(7 "B.SilkS" user "Ref Des/Silkscreen Bottom")
		(1 "F.Mask" user "Board Geometry/Soldermask Top")
		(3 "B.Mask" user "Board Geometry/Soldermask Bottom")
		(17 "Dwgs.User" user "User.Drawings")
		(19 "Cmts.User" user "User.Comments")
		(21 "Eco1.User" user "User.Eco1")
		(23 "Eco2.User" user "User.Eco2")
		(25 "Edge.Cuts" user "Board Geometry/Outline")
		(27 "Margin" user)
		(31 "F.CrtYd" user "Package Geometry/Place Bound Top")
		(29 "B.CrtYd" user "Package Geometry/Place Bound Bottom")
		(35 "F.Fab" user "Ref Des/Assembly Top")
		(33 "B.Fab" user "Ref Des/Assembly Bottom")
	)
	(footprint ""
		(layer "F.Cu")
		(at 27.723084 -91.314016 90)
		(property "Reference" "U83"
			(at 0 0 90)
			(layer "F.SilkS")
			(hide yes)
			(effects
				(font
					(size 1.27 1.27)
				)
			)
		)
		(property "Value" "SN74LVC1G08DCKR-GP"
			(at -2.3368 -8.6868 90)
			(unlocked yes)
			(layer "F.Fab")
			(hide yes)
			(effects
				(font
					(size 1.016 1.016)
					(thickness 0.1524)
				)
			)
		)
		(property "Device Type" "SC70-5H44"
			(at -2.3114 -10.414 90)
			(unlocked yes)
			(layer "F.Fab")
			(hide yes)
			(effects
				(font
					(size 1.016 1.016)
					(thickness 0.1524)
				)
			)
		)
		(duplicate_pad_numbers_are_jumpers no)
		(fp_line
			(start 1.3843 -1.8034)
			(end 1.3843 -1.1176)
			(stroke
				(width 0.3302)
				(type default)
			)
			(layer "F.SilkS")
		)
		(fp_line
			(start 0.6604 -1.8034)
			(end 1.3843 -1.8034)
			(stroke
				(width 0.3302)
				(type default)
			)
			(layer "F.SilkS")
		)
		(fp_line
			(start 1.27 -1.7018)
			(end 1.27 1.7018)
			(stroke
				(width 0.1524)
				(type default)
			)
			(layer "F.SilkS")
		)
		(fp_line
			(start -1.27 -1.7018)
			(end 1.27 -1.7018)
			(stroke
				(width 0.1524)
				(type default)
			)
			(layer "F.SilkS")
		)
		(fp_line
			(start 1.27 1.7018)
			(end -1.27 1.7018)
			(stroke
				(width 0.1524)
				(type default)
			)
			(layer "F.SilkS")
		)
		(fp_line
			(start -1.27 1.7018)
			(end -1.27 -1.7018)
			(stroke
				(width 0.1524)
				(type default)
			)
			(layer "F.SilkS")
		)
		(fp_rect
			(start -1.524 1.9558)
			(end 1.524 -1.9558)
			(stroke
				(width 0)
				(type default)
			)
			(fill no)
			(layer "F.CrtYd")
		)
		(fp_poly
			(pts
				(xy -1.524 -1.9558) (xy 1.524 -1.9558) (xy 1.524 1.9558) (xy -1.524 1.9558)
			)
			(stroke
				(width 0)
				(type default)
			)
			(fill no)
			(layer "F.Fab")
		)
		(pad "1" smd rect
			(at 0.65024 -0.8255 90)
			(size 0.4064 1.2192)
			(layers "F.Cu" "F.Mask" "F.Paste")
			(net "FM_BMC_RESET_N")
		)
		(pad "2" smd rect
			(at 0 -0.8255 90)
			(size 0.4064 1.2192)
			(layers "F.Cu" "F.Mask" "F.Paste")
			(net "BMC_I210_PERST_N")
		)
		(pad "3" smd rect
			(at -0.65024 -0.8255 90)
			(size 0.4064 1.2192)
			(layers "F.Cu" "F.Mask" "F.Paste")
			(net "GND")
		)
		(pad "4" smd rect
			(at -0.65024 0.8255 90)
			(size 0.4064 1.2192)
			(layers "F.Cu" "F.Mask" "F.Paste")
			(net "I210_PERST_N")
		)
		(pad "5" smd rect
			(at 0.65024 0.8255 90)
			(size 0.4064 1.2192)
			(layers "F.Cu" "F.Mask" "F.Paste")
			(net "P3V3_STBY")
		)
	)
	(footprint ""
		(layer "F.Cu")
		(at 19.2532 -68.4784 -90)
		(property "Reference" "TP150"
			(at 0 0 270)
			(layer "F.SilkS")
			(hide yes)
			(effects
				(font
					(size 1.27 1.27)
				)
			)
		)
		(property "Value" "TPAD28-2-GP"
			(at -0.0127 -1.6637 270)
			(unlocked yes)
			(layer "F.Fab")
			(hide yes)
			(effects
				(font
					(size 1.016 1.016)
					(thickness 0.1524)
				)
			)
		)
		(property "Device Type" "TPAD28"
			(at -0.0127 -3.1877 270)
			(unlocked yes)
			(layer "F.Fab")
			(hide yes)
			(effects
				(font
					(size 1.016 1.016)
					(thickness 0.1524)
				)
			)
		)
		(duplicate_pad_numbers_are_jumpers no)
		(fp_poly
			(pts
				(arc
					(start 0 -0.3556)
					(mid 0 0.3556)
					(end 0 -0.3556)
				)
			)
			(stroke
				(width 0)
				(type default)
			)
			(fill no)
			(layer "F.CrtYd")
		)
		(fp_poly
			(pts
				(arc
					(start 0 -0.6096)
					(mid 0 0.6096)
					(end 0 -0.6096)
				)
			)
			(stroke
				(width 0)
				(type default)
			)
			(fill no)
			(layer "F.Fab")
		)
		(pad "1" smd circle
			(at 0 0 270)
			(size 0.7112 0.7112)
			(layers "F.Cu" "F.Mask" "F.Paste")
			(net "TP_SDP3")
		)
	)
	(footprint ""
		(layer "F.Cu")
		(at 72.771 -197.612 180)
		(property "Reference" "R7976"
			(at 0 0 180)
			(layer "F.SilkS")
			(hide yes)
			(effects
				(font
					(size 1.27 1.27)
				)
			)
		)
		(property "Value" "0R2J-2-GP"
			(at 0.064008 -3.993896 180)
			(unlocked yes)
			(layer "F.Fab")
			(hide yes)
			(effects
				(font
					(size 1.016 1.016)
					(thickness 0.1524)
				)
			)
		)
		(property "Device Type" "R402H16"
			(at 0.064008 -5.517896 180)
			(unlocked yes)
			(layer "F.Fab")
			(hide yes)
			(effects
				(font
					(size 1.016 1.016)
					(thickness 0.1524)
				)
			)
		)
		(duplicate_pad_numbers_are_jumpers no)
		(fp_line
			(start 0.508 -0.9398)
			(end -0.508 -0.9398)
			(stroke
				(width 0.1524)
				(type default)
			)
			(layer "F.SilkS")
		)
		(fp_line
			(start -0.508 -0.9398)
			(end -0.508 0.9398)
			(stroke
				(width 0.1524)
				(type default)
			)
			(layer "F.SilkS")
		)
		(fp_rect
			(start -0.508 0.9398)
			(end 0.508 -0.9398)
			(stroke
				(width 0)
				(type default)
			)
			(fill no)
			(layer "F.CrtYd")
		)
		(fp_rect
			(start -0.508 0.9398)
			(end 0.508 -0.9398)
			(stroke
				(width 0)
				(type default)
			)
			(fill no)
			(layer "F.Fab")
		)
		(pad "1" smd custom
			(at 0 -0.4445 180)
			(size 0.1397 0.1397)
			(layers "F.Cu" "F.Mask" "F.Paste")
			(net "SSD_PERST#11")
			(options
				(clearance outline)
				(anchor circle)
			)
			(primitives
				(gr_poly
					(pts
						(arc
							(start -0.1778 -0.2794)
							(mid -0.249642 -0.249642)
							(end -0.2794 -0.1778)
						)
						(arc
							(start -0.2794 0.1778)
							(mid -0.249642 0.249642)
							(end -0.1778 0.2794)
						)
						(arc
							(start 0.1778 0.2794)
							(mid 0.249642 0.249642)
							(end 0.2794 0.1778)
						)
						(arc
							(start 0.2794 -0.1778)
							(mid 0.249642 -0.249642)
							(end 0.1778 -0.2794)
						)
					)
					(width 0)
					(fill yes)
				)
			)
		)
		(pad "2" smd custom
			(at 0 0.4445 180)
			(size 0.1397 0.1397)
			(layers "F.Cu" "F.Mask" "F.Paste")
			(net "SSD_PERST#11_R")
			(options
				(clearance outline)
				(anchor circle)
			)
			(primitives
				(gr_poly
					(pts
						(arc
							(start -0.1778 -0.2794)
							(mid -0.249642 -0.249642)
							(end -0.2794 -0.1778)
						)
						(arc
							(start -0.2794 0.1778)
							(mid -0.249642 0.249642)
							(end -0.1778 0.2794)
						)
						(arc
							(start 0.1778 0.2794)
							(mid 0.249642 0.249642)
							(end 0.2794 0.1778)
						)
						(arc
							(start 0.2794 -0.1778)
							(mid 0.249642 -0.249642)
							(end 0.1778 -0.2794)
						)
					)
					(width 0)
					(fill yes)
				)
			)
		)
	)
	(footprint ""
		(layer "F.Cu")
		(at 70.1802 -164.5666 180)
		(property "Reference" "PC20"
			(at 0 0 180)
			(layer "F.SilkS")
			(hide yes)
			(effects
				(font
					(size 1.27 1.27)
				)
			)
		)
		(property "Value" "SC10U10V5KX-6-GP-U"
			(at -0.0762 -6.1214 180)
			(unlocked yes)
			(layer "F.Fab")
			(hide yes)
			(effects
				(font
					(size 1.016 1.016)
					(thickness 0.1524)
				)
			)
		)
		(property "Device Type" "C805H58"
			(at -0.0762 -8.1534 180)
			(unlocked yes)
			(layer "F.Fab")
			(hide yes)
			(effects
				(font
					(size 1.016 1.016)
					(thickness 0.1524)
				)
			)
		)
		(duplicate_pad_numbers_are_jumpers no)
		(fp_line
			(start 0.635 0)
			(end -0.635 0)
			(stroke
				(width 0.508)
				(type default)
			)
			(layer "F.SilkS")
		)
		(fp_rect
			(start -0.9652 1.778)
			(end 0.9652 -1.778)
			(stroke
				(width 0)
				(type default)
			)
			(fill no)
			(layer "F.CrtYd")
		)
		(fp_poly
			(pts
				(xy -0.9652 -1.778) (xy 0.9652 -1.778) (xy 0.9652 1.778) (xy -0.9652 1.778)
			)
			(stroke
				(width 0)
				(type default)
			)
			(fill no)
			(layer "F.Fab")
		)
		(pad "1" smd rect
			(at 0 -0.9652 180)
			(size 1.397 1.143)
			(layers "F.Cu" "F.Mask" "F.Paste")
			(net "VR_P1V538_STBY_BIAS")
		)
		(pad "2" smd rect
			(at 0 0.9652 180)
			(size 1.397 1.143)
			(layers "F.Cu" "F.Mask" "F.Paste")
			(net "GND")
		)
	)
	(footprint ""
		(layer "F.Cu")
		(at 70.1802 -161.2646 90)
		(property "Reference" "PC76"
			(at 0 0 90)
			(layer "F.SilkS")
			(hide yes)
			(effects
				(font
					(size 1.27 1.27)
				)
			)
		)
		(property "Value" "SC1KP50V2KX-1GP"
			(at 1.1811 -2.7051 90)
			(unlocked yes)
			(layer "F.Fab")
			(hide yes)
			(effects
				(font
					(size 1.016 1.016)
					(thickness 0.1524)
				)
			)
		)
		(property "Device Type" "C402H22"
			(at 1.1811 -4.2291 90)
			(unlocked yes)
			(layer "F.Fab")
			(hide yes)
			(effects
				(font
					(size 1.016 1.016)
					(thickness 0.1524)
				)
			)
		)
		(duplicate_pad_numbers_are_jumpers no)
		(fp_rect
			(start -0.4318 0.9525)
			(end 0.4318 -0.9525)
			(stroke
				(width 0)
				(type default)
			)
			(fill no)
			(layer "F.CrtYd")
		)
		(fp_rect
			(start -0.4318 0.9525)
			(end 0.4318 -0.9525)
			(stroke
				(width 0)
				(type default)
			)
			(fill no)
			(layer "F.Fab")
		)
		(pad "1" smd custom
			(at 0 -0.4445 90)
			(size 0.1524 0.1524)
			(layers "F.Cu" "F.Mask" "F.Paste")
			(net "PWRGD_P1V538_STBY")
			(options
				(clearance outline)
				(anchor circle)
			)
			(primitives
				(gr_poly
					(pts
						(arc
							(start 0.3048 -0.2032)
							(mid 0.275042 -0.275042)
							(end 0.2032 -0.3048)
						)
						(arc
							(start -0.2032 -0.3048)
							(mid -0.275042 -0.275042)
							(end -0.3048 -0.2032)
						)
						(arc
							(start -0.3048 0.2032)
							(mid -0.275042 0.275042)
							(end -0.2032 0.3048)
						)
						(arc
							(start 0.2032 0.3048)
							(mid 0.275042 0.275042)
							(end 0.3048 0.2032)
						)
					)
					(width 0)
					(fill yes)
				)
			)
		)
		(pad "2" smd custom
			(at 0 0.4445 90)
			(size 0.1524 0.1524)
			(layers "F.Cu" "F.Mask" "F.Paste")
			(net "GND")
			(options
				(clearance outline)
				(anchor circle)
			)
			(primitives
				(gr_poly
					(pts
						(arc
							(start 0.3048 -0.2032)
							(mid 0.275042 -0.275042)
							(end 0.2032 -0.3048)
						)
						(arc
							(start -0.2032 -0.3048)
							(mid -0.275042 -0.275042)
							(end -0.3048 -0.2032)
						)
						(arc
							(start -0.3048 0.2032)
							(mid -0.275042 0.275042)
							(end -0.2032 0.3048)
						)
						(arc
							(start 0.2032 0.3048)
							(mid 0.275042 0.275042)
							(end 0.3048 0.2032)
						)
					)
					(width 0)
					(fill yes)
				)
			)
		)
	)
	(footprint ""
		(layer "F.Cu")
		(at 122.023124 -208.889092 180)
		(property "Reference" "C3208"
			(at 0 0 180)
			(layer "F.SilkS")
			(hide yes)
			(effects
				(font
					(size 1.27 1.27)
				)
			)
		)
		(property "Value" "SCD1U25V2KX-2-GP"
			(at 1.1811 -2.7051 180)
			(unlocked yes)
			(layer "F.Fab")
			(hide yes)
			(effects
				(font
					(size 1.016 1.016)
					(thickness 0.1524)
				)
			)
		)
		(property "Device Type" "C402H22"
			(at 1.1811 -4.2291 180)
			(unlocked yes)
			(layer "F.Fab")
			(hide yes)
			(effects
				(font
					(size 1.016 1.016)
					(thickness 0.1524)
				)
			)
		)
		(duplicate_pad_numbers_are_jumpers no)
		(fp_rect
			(start -0.4318 0.9525)
			(end 0.4318 -0.9525)
			(stroke
				(width 0)
				(type default)
			)
			(fill no)
			(layer "F.CrtYd")
		)
		(fp_rect
			(start -0.4318 0.9525)
			(end 0.4318 -0.9525)
			(stroke
				(width 0)
				(type default)
			)
			(fill no)
			(layer "F.Fab")
		)
		(pad "1" smd custom
			(at 0 -0.4445 180)
			(size 0.1524 0.1524)
			(layers "F.Cu" "F.Mask" "F.Paste")
			(net "P3V3_STBY")
			(options
				(clearance outline)
				(anchor circle)
			)
			(primitives
				(gr_poly
					(pts
						(arc
							(start 0.3048 -0.2032)
							(mid 0.275042 -0.275042)
							(end 0.2032 -0.3048)
						)
						(arc
							(start -0.2032 -0.3048)
							(mid -0.275042 -0.275042)
							(end -0.3048 -0.2032)
						)
						(arc
							(start -0.3048 0.2032)
							(mid -0.275042 0.275042)
							(end -0.2032 0.3048)
						)
						(arc
							(start 0.2032 0.3048)
							(mid 0.275042 0.275042)
							(end 0.3048 0.2032)
						)
					)
					(width 0)
					(fill yes)
				)
			)
		)
		(pad "2" smd custom
			(at 0 0.4445 180)
			(size 0.1524 0.1524)
			(layers "F.Cu" "F.Mask" "F.Paste")
			(net "GND")
			(options
				(clearance outline)
				(anchor circle)
			)
			(primitives
				(gr_poly
					(pts
						(arc
							(start 0.3048 -0.2032)
							(mid 0.275042 -0.275042)
							(end 0.2032 -0.3048)
						)
						(arc
							(start -0.2032 -0.3048)
							(mid -0.275042 -0.275042)
							(end -0.3048 -0.2032)
						)
						(arc
							(start -0.3048 0.2032)
							(mid -0.275042 0.275042)
							(end -0.2032 0.3048)
						)
						(arc
							(start 0.2032 0.3048)
							(mid 0.275042 0.275042)
							(end 0.3048 0.2032)
						)
					)
					(width 0)
					(fill yes)
				)
			)
		)
	)
	(footprint ""
		(layer "F.Cu")
		(at 22.4536 -55.118 180)
		(property "Reference" "R612"
			(at 0 0 180)
			(layer "F.SilkS")
			(hide yes)
			(effects
				(font
					(size 1.27 1.27)
				)
			)
		)
		(property "Value" "0R2J-2-GP"
			(at 0.064008 -3.993896 180)
			(unlocked yes)
			(layer "F.Fab")
			(hide yes)
			(effects
				(font
					(size 1.016 1.016)
					(thickness 0.1524)
				)
			)
		)
		(property "Device Type" "R402H16"
			(at 0.064008 -5.517896 180)
			(unlocked yes)
			(layer "F.Fab")
			(hide yes)
			(effects
				(font
					(size 1.016 1.016)
					(thickness 0.1524)
				)
			)
		)
		(duplicate_pad_numbers_are_jumpers no)
		(fp_line
			(start 0.508 -0.9398)
			(end -0.508 -0.9398)
			(stroke
				(width 0.1524)
				(type default)
			)
			(layer "F.SilkS")
		)
		(fp_line
			(start -0.508 -0.9398)
			(end -0.508 0.9398)
			(stroke
				(width 0.1524)
				(type default)
			)
			(layer "F.SilkS")
		)
		(fp_rect
			(start -0.508 0.9398)
			(end 0.508 -0.9398)
			(stroke
				(width 0)
				(type default)
			)
			(fill no)
			(layer "F.CrtYd")
		)
		(fp_rect
			(start -0.508 0.9398)
			(end 0.508 -0.9398)
			(stroke
				(width 0)
				(type default)
			)
			(fill no)
			(layer "F.Fab")
		)
		(pad "1" smd custom
			(at 0 -0.4445 180)
			(size 0.1397 0.1397)
			(layers "F.Cu" "F.Mask" "F.Paste")
			(net "NIC0_MDI0_N3")
			(options
				(clearance outline)
				(anchor circle)
			)
			(primitives
				(gr_poly
					(pts
						(arc
							(start -0.1778 -0.2794)
							(mid -0.249642 -0.249642)
							(end -0.2794 -0.1778)
						)
						(arc
							(start -0.2794 0.1778)
							(mid -0.249642 0.249642)
							(end -0.1778 0.2794)
						)
						(arc
							(start 0.1778 0.2794)
							(mid 0.249642 0.249642)
							(end 0.2794 0.1778)
						)
						(arc
							(start 0.2794 -0.1778)
							(mid 0.249642 -0.249642)
							(end 0.1778 -0.2794)
						)
					)
					(width 0)
					(fill yes)
				)
			)
		)
		(pad "2" smd custom
			(at 0 0.4445 180)
			(size 0.1397 0.1397)
			(layers "F.Cu" "F.Mask" "F.Paste")
			(net "MNG_RX_DN")
			(options
				(clearance outline)
				(anchor circle)
			)
			(primitives
				(gr_poly
					(pts
						(arc
							(start -0.1778 -0.2794)
							(mid -0.249642 -0.249642)
							(end -0.2794 -0.1778)
						)
						(arc
							(start -0.2794 0.1778)
							(mid -0.249642 0.249642)
							(end -0.1778 0.2794)
						)
						(arc
							(start 0.1778 0.2794)
							(mid 0.249642 0.249642)
							(end 0.2794 0.1778)
						)
						(arc
							(start 0.2794 -0.1778)
							(mid 0.249642 -0.249642)
							(end 0.1778 -0.2794)
						)
					)
					(width 0)
					(fill yes)
				)
			)
		)
	)
	(footprint ""
		(layer "F.Cu")
		(at 143.136874 -95.27032)
		(property "Reference" "PR78"
			(at 0 0 0)
			(layer "F.SilkS")
			(hide yes)
			(effects
				(font
					(size 1.27 1.27)
				)
			)
		)
		(property "Value" "10KR2F-2-GP"
			(at 0.064008 -3.993896 0)
			(unlocked yes)
			(layer "F.Fab")
			(hide yes)
			(effects
				(font
					(size 1.016 1.016)
					(thickness 0.1524)
				)
			)
		)
		(property "Device Type" "R402H16"
			(at 0.064008 -5.517896 0)
			(unlocked yes)
			(layer "F.Fab")
			(hide yes)
			(effects
				(font
					(size 1.016 1.016)
					(thickness 0.1524)
				)
			)
		)
		(duplicate_pad_numbers_are_jumpers no)
		(fp_line
			(start -0.508 -0.9398)
			(end -0.508 0.9398)
			(stroke
				(width 0.1524)
				(type default)
			)
			(layer "F.SilkS")
		)
		(fp_line
			(start 0.508 -0.9398)
			(end -0.508 -0.9398)
			(stroke
				(width 0.1524)
				(type default)
			)
			(layer "F.SilkS")
		)
		(fp_rect
			(start -0.508 0.9398)
			(end 0.508 -0.9398)
			(stroke
				(width 0)
				(type default)
			)
			(fill no)
			(layer "F.CrtYd")
		)
		(fp_rect
			(start -0.508 0.9398)
			(end 0.508 -0.9398)
			(stroke
				(width 0)
				(type default)
			)
			(fill no)
			(layer "F.Fab")
		)
		(pad "1" smd custom
			(at 0 -0.4445)
			(size 0.1397 0.1397)
			(layers "F.Cu" "F.Mask" "F.Paste")
			(net "P3V3_STBY")
			(options
				(clearance outline)
				(anchor circle)
			)
			(primitives
				(gr_poly
					(pts
						(arc
							(start -0.1778 -0.2794)
							(mid -0.249642 -0.249642)
							(end -0.2794 -0.1778)
						)
						(arc
							(start -0.2794 0.1778)
							(mid -0.249642 0.249642)
							(end -0.1778 0.2794)
						)
						(arc
							(start 0.1778 0.2794)
							(mid 0.249642 0.249642)
							(end 0.2794 0.1778)
						)
						(arc
							(start 0.2794 -0.1778)
							(mid 0.249642 -0.249642)
							(end 0.1778 -0.2794)
						)
					)
					(width 0)
					(fill yes)
				)
			)
		)
		(pad "2" smd custom
			(at 0 0.4445)
			(size 0.1397 0.1397)
			(layers "F.Cu" "F.Mask" "F.Paste")
			(net "PWRGD_P1V8_STBY")
			(options
				(clearance outline)
				(anchor circle)
			)
			(primitives
				(gr_poly
					(pts
						(arc
							(start -0.1778 -0.2794)
							(mid -0.249642 -0.249642)
							(end -0.2794 -0.1778)
						)
						(arc
							(start -0.2794 0.1778)
							(mid -0.249642 0.249642)
							(end -0.1778 0.2794)
						)
						(arc
							(start 0.1778 0.2794)
							(mid 0.249642 0.249642)
							(end 0.2794 0.1778)
						)
						(arc
							(start 0.2794 -0.1778)
							(mid 0.249642 -0.249642)
							(end 0.1778 -0.2794)
						)
					)
					(width 0)
					(fill yes)
				)
			)
		)
	)
)
